(kicad_pcb
	(version 20260206)
	(generator "pcbnew")
	(generator_version "10.0")
	(general
		(thickness 1.6)
		(legacy_teardrops no)
	)
	(paper "A4")
	(title_block
		(title "v2-pdb — ms_pdb_v2.brd")
		(comment 1 "Open CloudServer (Microsoft) / footprints 95-95 of 348")
	)
	(layers
		(0 "F.Cu" signal "TOP")
		(4 "In1.Cu" signal "GND")
		(6 "In2.Cu" signal "IN1")
		(8 "In3.Cu" signal "VCC")
		(10 "In4.Cu" signal "VCC1")
		(12 "In5.Cu" signal "IN2")
		(14 "In6.Cu" signal "GND1")
		(2 "B.Cu" signal "BOTTOM")
		(9 "F.Adhes" user "F.Adhesive")
		(11 "B.Adhes" user "B.Adhesive")
		(13 "F.Paste" user "Package Geometry/Pastemask Top")
		(15 "B.Paste" user "Package Geometry/Pastemask Bottom")
		(5 "F.SilkS" user "Ref Des/Silkscreen Top")
		(7 "B.SilkS" user "Ref Des/Silkscreen Bottom")
		(1 "F.Mask" user "Board Geometry/Soldermask Top")
		(3 "B.Mask" user "Board Geometry/Soldermask Bottom")
		(17 "Dwgs.User" user "User.Drawings")
		(19 "Cmts.User" user "User.Comments")
		(21 "Eco1.User" user "User.Eco1")
		(23 "Eco2.User" user "User.Eco2")
		(25 "Edge.Cuts" user "Board Geometry/Outline")
		(27 "Margin" user)
		(31 "F.CrtYd" user "Package Geometry/Place Bound Top")
		(29 "B.CrtYd" user "Package Geometry/Place Bound Bottom")
		(35 "F.Fab" user "Ref Des/Assembly Top")
		(33 "B.Fab" user "Ref Des/Assembly Bottom")
	)
	(footprint ""
		(layer "F.Cu")
		(at 30.45968 -436.930038)
		(property "Reference" "J5"
			(at -4.20243 -2.774188 0)
			(unlocked yes)
			(layer "F.SilkS")
			(effects
				(font
					(size 0.7874 0.5842)
					(thickness 0.1524)
				)
				(justify left)
			)
		)
		(property "Value" ""
			(at 0 0 0)
			(layer "F.Fab")
			(effects
				(font
					(size 1.27 1.27)
				)
			)
		)
		(duplicate_pad_numbers_are_jumpers no)
		(fp_line
			(start -2.135124 -4.560062)
			(end -2.135124 83.300062)
			(stroke
				(width 0.1524)
				(type default)
			)
			(layer "F.SilkS")
		)
		(fp_line
			(start -2.135124 83.300062)
			(end 7.215124 83.300062)
			(stroke
				(width 0.1524)
				(type default)
			)
			(layer "F.SilkS")
		)
		(fp_line
			(start 7.215124 -4.560062)
			(end -2.135124 -4.560062)
			(stroke
				(width 0.1524)
				(type default)
			)
			(layer "F.SilkS")
		)
		(fp_line
			(start 7.215124 83.300062)
			(end 7.215124 -4.560062)
			(stroke
				(width 0.1524)
				(type default)
			)
			(layer "F.SilkS")
		)
		(fp_poly
			(pts
				(xy -2.74447 -0.00889) (xy -5.44449 -0.708914) (xy -5.44449 0.691134)
			)
			(stroke
				(width 0)
				(type default)
			)
			(fill yes)
			(layer "F.SilkS")
		)
		(fp_poly
			(pts
				(xy -2.28219 -0.127) (xy -4.98221 -0.827024) (xy -4.98221 0.573024)
			)
			(stroke
				(width 0)
				(type default)
			)
			(fill yes)
			(layer "B.SilkS")
		)
		(fp_poly
			(pts
				(xy -0.8636 -0.8636) (xy -0.8636 79.6036) (xy -0.8636 79.629) (xy 5.9436 79.629) (xy 5.9436 79.6036)
				(xy 5.9436 -0.8636) (xy 5.9436 -0.889) (xy -0.8636 -0.889)
			)
			(stroke
				(width 0)
				(type default)
			)
			(fill no)
			(layer "B.CrtYd")
		)
		(fp_rect
			(start -2.135124 -4.560062)
			(end 7.21487 83.300062)
			(stroke
				(width 0)
				(type default)
			)
			(fill no)
			(layer "F.CrtYd")
		)
		(fp_line
			(start -2.135124 -4.560062)
			(end 7.215124 -4.560062)
			(stroke
				(width 0.1)
				(type default)
			)
			(layer "F.Fab")
		)
		(fp_line
			(start -2.135124 83.300062)
			(end -2.135124 -4.560062)
			(stroke
				(width 0.1)
				(type default)
			)
			(layer "F.Fab")
		)
		(fp_line
			(start 7.215124 -4.560062)
			(end 7.215124 83.300062)
			(stroke
				(width 0.1)
				(type default)
			)
			(layer "F.Fab")
		)
		(fp_line
			(start 7.215124 83.300062)
			(end -2.135124 83.300062)
			(stroke
				(width 0.1)
				(type default)
			)
			(layer "F.Fab")
		)
		(fp_text user "32"
			(at -3.655568 78.848458 0)
			(unlocked yes)
			(layer "F.SilkS")
			(effects
				(font
					(size 0.7874 0.5842)
					(thickness 0.1524)
				)
				(justify left)
			)
		)
		(fp_text user "1"
			(at -3.370834 -1.059434 0)
			(unlocked yes)
			(layer "F.SilkS")
			(effects
				(font
					(size 0.7874 0.5842)
					(thickness 0.1524)
				)
				(justify left)
			)
		)
		(fp_text user "33"
			(at 7.649464 81.833466 0)
			(unlocked yes)
			(layer "F.SilkS")
			(effects
				(font
					(size 0.7874 0.5842)
					(thickness 0.1524)
				)
				(justify left)
			)
		)
		(fp_text user "64"
			(at 7.771638 -0.257048 0)
			(unlocked yes)
			(layer "F.SilkS")
			(effects
				(font
					(size 0.7874 0.5842)
					(thickness 0.1524)
				)
				(justify left)
			)
		)
		(fp_text user "32"
			(at -1.12649 78.817216 0)
			(unlocked yes)
			(layer "B.SilkS")
			(effects
				(font
					(size 0.7874 0.5842)
					(thickness 0.1524)
				)
				(justify left mirror)
			)
		)
		(fp_text user "1"
			(at -1.029208 -1.200912 0)
			(unlocked yes)
			(layer "B.SilkS")
			(effects
				(font
					(size 0.7874 0.5842)
					(thickness 0.1524)
				)
				(justify left mirror)
			)
		)
		(fp_text user "33"
			(at 5.666486 81.833466 0)
			(unlocked yes)
			(layer "B.SilkS")
			(effects
				(font
					(size 0.7874 0.5842)
					(thickness 0.1524)
				)
				(justify left mirror)
			)
		)
		(fp_text user "64"
			(at 5.904992 -1.819148 0)
			(unlocked yes)
			(layer "B.SilkS")
			(effects
				(font
					(size 0.7874 0.5842)
					(thickness 0.1524)
				)
				(justify left mirror)
			)
		)
		(pad "1" thru_hole rect
			(at 0 0 270)
			(size 1.6256 1.6256)
			(drill 1.1176)
			(layers "*.Cu" "*.Mask")
			(remove_unused_layers no)
			(net "P12V")
			(clearance 0)
			(padstack
				(mode front_inner_back)
				(layer "Inner"
					(shape circle)
					(size 1.6256 1.6256)
					(clearance 0)
				)
				(layer "B.Cu"
					(shape rect)
					(size 1.6256 1.6256)
					(clearance 0)
				)
			)
		)
		(pad "2" thru_hole circle
			(at 0 2.54 270)
			(size 1.6256 1.6256)
			(drill 1.1176)
			(layers "*.Cu" "*.Mask")
			(remove_unused_layers no)
			(net "P12V")
			(clearance 0)
		)
		(pad "3" thru_hole circle
			(at 0 5.08 270)
			(size 1.6256 1.6256)
			(drill 1.1176)
			(layers "*.Cu" "*.Mask")
			(remove_unused_layers no)
			(net "P12V")
			(clearance 0)
		)
		(pad "4" thru_hole circle
			(at 0 7.62 270)
			(size 1.6256 1.6256)
			(drill 1.1176)
			(layers "*.Cu" "*.Mask")
			(remove_unused_layers no)
			(net "P12V")
			(clearance 0)
		)
		(pad "5" thru_hole circle
			(at 0 10.16 270)
			(size 1.6256 1.6256)
			(drill 1.1176)
			(layers "*.Cu" "*.Mask")
			(remove_unused_layers no)
			(net "P12V")
			(clearance 0)
		)
		(pad "6" thru_hole circle
			(at 0 12.7 270)
			(size 1.6256 1.6256)
			(drill 1.1176)
			(layers "*.Cu" "*.Mask")
			(remove_unused_layers no)
			(net "P12V")
			(clearance 0)
		)
		(pad "7" thru_hole circle
			(at 0 15.24 270)
			(size 1.6256 1.6256)
			(drill 1.1176)
			(layers "*.Cu" "*.Mask")
			(remove_unused_layers no)
			(net "P12V")
			(clearance 0)
		)
		(pad "8" thru_hole circle
			(at 0 17.78 270)
			(size 1.6256 1.6256)
			(drill 1.1176)
			(layers "*.Cu" "*.Mask")
			(remove_unused_layers no)
			(net "P12V")
			(clearance 0)
		)
		(pad "9" thru_hole circle
			(at 0 20.32 270)
			(size 1.6256 1.6256)
			(drill 1.1176)
			(layers "*.Cu" "*.Mask")
			(remove_unused_layers no)
			(net "P12V")
			(clearance 0)
		)
		(pad "10" thru_hole circle
			(at 0 22.86 270)
			(size 1.6256 1.6256)
			(drill 1.1176)
			(layers "*.Cu" "*.Mask")
			(remove_unused_layers no)
			(net "P12V")
			(clearance 0)
		)
		(pad "11" thru_hole circle
			(at 0 25.4 270)
			(size 1.6256 1.6256)
			(drill 1.1176)
			(layers "*.Cu" "*.Mask")
			(remove_unused_layers no)
			(net "P12V")
			(clearance 0)
		)
		(pad "12" thru_hole circle
			(at 0 27.94 270)
			(size 1.6256 1.6256)
			(drill 1.1176)
			(layers "*.Cu" "*.Mask")
			(remove_unused_layers no)
			(net "P12V")
			(clearance 0)
		)
		(pad "13" thru_hole circle
			(at 0 30.48 270)
			(size 1.6256 1.6256)
			(drill 1.1176)
			(layers "*.Cu" "*.Mask")
			(remove_unused_layers no)
			(net "GND")
			(clearance 0)
		)
		(pad "14" thru_hole circle
			(at 0 33.02 270)
			(size 1.6256 1.6256)
			(drill 1.1176)
			(layers "*.Cu" "*.Mask")
			(remove_unused_layers no)
			(net "GND")
			(clearance 0)
		)
		(pad "15" thru_hole circle
			(at 0 35.56 270)
			(size 1.6256 1.6256)
			(drill 1.1176)
			(layers "*.Cu" "*.Mask")
			(remove_unused_layers no)
			(net "GND")
			(clearance 0)
		)
		(pad "16" thru_hole circle
			(at 0 38.1 270)
			(size 1.6256 1.6256)
			(drill 1.1176)
			(layers "*.Cu" "*.Mask")
			(remove_unused_layers no)
			(net "GND")
			(clearance 0)
		)
		(pad "17" thru_hole circle
			(at 0 40.64 270)
			(size 1.6256 1.6256)
			(drill 1.1176)
			(layers "*.Cu" "*.Mask")
			(remove_unused_layers no)
			(net "GND")
			(clearance 0)
		)
		(pad "18" thru_hole circle
			(at 0 43.18 270)
			(size 1.6256 1.6256)
			(drill 1.1176)
			(layers "*.Cu" "*.Mask")
			(remove_unused_layers no)
			(net "GND")
			(clearance 0)
		)
		(pad "19" thru_hole circle
			(at 0 45.72 270)
			(size 1.6256 1.6256)
			(drill 1.1176)
			(layers "*.Cu" "*.Mask")
			(remove_unused_layers no)
			(net "GND")
			(clearance 0)
		)
		(pad "20" thru_hole circle
			(at 0 48.26 270)
			(size 1.6256 1.6256)
			(drill 1.1176)
			(layers "*.Cu" "*.Mask")
			(remove_unused_layers no)
			(net "GND")
			(clearance 0)
		)
		(pad "21" thru_hole circle
			(at 0 50.8 270)
			(size 1.6256 1.6256)
			(drill 1.1176)
			(layers "*.Cu" "*.Mask")
			(remove_unused_layers no)
			(net "GND")
			(clearance 0)
		)
		(pad "22" thru_hole circle
			(at 0 53.34 270)
			(size 1.6256 1.6256)
			(drill 1.1176)
			(layers "*.Cu" "*.Mask")
			(remove_unused_layers no)
			(net "GND")
			(clearance 0)
		)
		(pad "23" thru_hole circle
			(at 0 55.88 270)
			(size 1.6256 1.6256)
			(drill 1.1176)
			(layers "*.Cu" "*.Mask")
			(remove_unused_layers no)
			(net "GND")
			(clearance 0)
		)
		(pad "24" thru_hole circle
			(at 0 58.42 270)
			(size 1.6256 1.6256)
			(drill 1.1176)
			(layers "*.Cu" "*.Mask")
			(remove_unused_layers no)
			(net "GND")
			(clearance 0)
		)
		(pad "25" thru_hole circle
			(at 0 60.96 270)
			(size 1.6256 1.6256)
			(drill 1.1176)
			(layers "*.Cu" "*.Mask")
			(remove_unused_layers no)
			(net "PHLOSS")
			(clearance 0)
		)
		(pad "26" thru_hole circle
			(at 0 63.5 270)
			(size 1.6256 1.6256)
			(drill 1.1176)
			(layers "*.Cu" "*.Mask")
			(remove_unused_layers no)
			(net "PSU5_REMOTE_N")
			(clearance 0)
		)
		(pad "27" thru_hole circle
			(at 0 66.04 270)
			(size 1.6256 1.6256)
			(drill 1.1176)
			(layers "*.Cu" "*.Mask")
			(remove_unused_layers no)
			(net "PSU5_AC_OK")
			(clearance 0)
		)
		(pad "28" thru_hole circle
			(at 0 68.58 270)
			(size 1.6256 1.6256)
			(drill 1.1176)
			(layers "*.Cu" "*.Mask")
			(remove_unused_layers no)
			(net "PSU5_CSAHRE")
			(clearance 0)
		)
		(pad "29" thru_hole circle
			(at 0 71.12 270)
			(size 1.6256 1.6256)
			(drill 1.1176)
			(layers "*.Cu" "*.Mask")
			(remove_unused_layers no)
			(net "PSU5_PS_ON_N")
			(clearance 0)
		)
		(pad "30" thru_hole circle
			(at 0 73.66 270)
			(size 1.6256 1.6256)
			(drill 1.1176)
			(layers "*.Cu" "*.Mask")
			(remove_unused_layers no)
			(net "PSU5_PS_KILL")
			(clearance 0)
		)
		(pad "31" thru_hole circle
			(at 0 76.2 270)
			(size 1.6256 1.6256)
			(drill 1.1176)
			(layers "*.Cu" "*.Mask")
			(remove_unused_layers no)
			(net "PSU5_RESET")
			(clearance 0)
		)
		(pad "32" thru_hole circle
			(at 0 78.74 270)
			(size 1.6256 1.6256)
			(drill 1.1176)
			(layers "*.Cu" "*.Mask")
			(remove_unused_layers no)
			(net "PSU_ALERT_N")
			(clearance 0)
		)
		(pad "33" thru_hole circle
			(at 5.08 78.74 270)
			(size 1.6256 1.6256)
			(drill 1.1176)
			(layers "*.Cu" "*.Mask")
			(remove_unused_layers no)
			(net "I2C_PSU3_SDA")
			(clearance 0)
		)
		(pad "34" thru_hole circle
			(at 5.08 76.2 270)
			(size 1.6256 1.6256)
			(drill 1.1176)
			(layers "*.Cu" "*.Mask")
			(remove_unused_layers no)
			(net "Net_426")
			(clearance 0)
		)
		(pad "35" thru_hole circle
			(at 5.08 73.66 270)
			(size 1.6256 1.6256)
			(drill 1.1176)
			(layers "*.Cu" "*.Mask")
			(remove_unused_layers no)
			(net "I2C_PSU3_SCL")
			(clearance 0)
		)
		(pad "36" thru_hole circle
			(at 5.08 71.12 270)
			(size 1.6256 1.6256)
			(drill 1.1176)
			(layers "*.Cu" "*.Mask")
			(remove_unused_layers no)
			(net "PSU5_RETURN")
			(clearance 0)
		)
		(pad "37" thru_hole circle
			(at 5.08 68.58 270)
			(size 1.6256 1.6256)
			(drill 1.1176)
			(layers "*.Cu" "*.Mask")
			(remove_unused_layers no)
			(net "PSU5_DC_OK")
			(clearance 0)
		)
		(pad "38" thru_hole circle
			(at 5.08 66.04 270)
			(size 1.6256 1.6256)
			(drill 1.1176)
			(layers "*.Cu" "*.Mask")
			(remove_unused_layers no)
			(net "PSU5_AD0")
			(clearance 0)
		)
		(pad "39" thru_hole circle
			(at 5.08 63.5 270)
			(size 1.6256 1.6256)
			(drill 1.1176)
			(layers "*.Cu" "*.Mask")
			(remove_unused_layers no)
			(net "P12V_STBY")
			(clearance 0)
		)
		(pad "40" thru_hole circle
			(at 5.08 60.96 270)
			(size 1.6256 1.6256)
			(drill 1.1176)
			(layers "*.Cu" "*.Mask")
			(remove_unused_layers no)
			(net "PSU5_REMOTE_P")
			(clearance 0)
		)
		(pad "41" thru_hole circle
			(at 5.08 58.42 270)
			(size 1.6256 1.6256)
			(drill 1.1176)
			(layers "*.Cu" "*.Mask")
			(remove_unused_layers no)
			(net "GND")
			(clearance 0)
		)
		(pad "42" thru_hole circle
			(at 5.08 55.88 270)
			(size 1.6256 1.6256)
			(drill 1.1176)
			(layers "*.Cu" "*.Mask")
			(remove_unused_layers no)
			(net "GND")
			(clearance 0)
		)
		(pad "43" thru_hole circle
			(at 5.08 53.34 270)
			(size 1.6256 1.6256)
			(drill 1.1176)
			(layers "*.Cu" "*.Mask")
			(remove_unused_layers no)
			(net "GND")
			(clearance 0)
		)
		(pad "44" thru_hole circle
			(at 5.08 50.8 270)
			(size 1.6256 1.6256)
			(drill 1.1176)
			(layers "*.Cu" "*.Mask")
			(remove_unused_layers no)
			(net "GND")
			(clearance 0)
		)
		(pad "45" thru_hole circle
			(at 5.08 48.26 270)
			(size 1.6256 1.6256)
			(drill 1.1176)
			(layers "*.Cu" "*.Mask")
			(remove_unused_layers no)
			(net "GND")
			(clearance 0)
		)
		(pad "46" thru_hole circle
			(at 5.08 45.72 270)
			(size 1.6256 1.6256)
			(drill 1.1176)
			(layers "*.Cu" "*.Mask")
			(remove_unused_layers no)
			(net "GND")
			(clearance 0)
		)
		(pad "47" thru_hole circle
			(at 5.08 43.18 270)
			(size 1.6256 1.6256)
			(drill 1.1176)
			(layers "*.Cu" "*.Mask")
			(remove_unused_layers no)
			(net "GND")
			(clearance 0)
		)
		(pad "48" thru_hole circle
			(at 5.08 40.64 270)
			(size 1.6256 1.6256)
			(drill 1.1176)
			(layers "*.Cu" "*.Mask")
			(remove_unused_layers no)
			(net "GND")
			(clearance 0)
		)
		(pad "49" thru_hole circle
			(at 5.08 38.1 270)
			(size 1.6256 1.6256)
			(drill 1.1176)
			(layers "*.Cu" "*.Mask")
			(remove_unused_layers no)
			(net "GND")
			(clearance 0)
		)
		(pad "50" thru_hole circle
			(at 5.08 35.56 270)
			(size 1.6256 1.6256)
			(drill 1.1176)
			(layers "*.Cu" "*.Mask")
			(remove_unused_layers no)
			(net "GND")
			(clearance 0)
		)
		(pad "51" thru_hole circle
			(at 5.08 33.02 270)
			(size 1.6256 1.6256)
			(drill 1.1176)
			(layers "*.Cu" "*.Mask")
			(remove_unused_layers no)
			(net "GND")
			(clearance 0)
		)
		(pad "52" thru_hole circle
			(at 5.08 30.48 270)
			(size 1.6256 1.6256)
			(drill 1.1176)
			(layers "*.Cu" "*.Mask")
			(remove_unused_layers no)
			(net "GND")
			(clearance 0)
		)
		(pad "53" thru_hole circle
			(at 5.08 27.94 270)
			(size 1.6256 1.6256)
			(drill 1.1176)
			(layers "*.Cu" "*.Mask")
			(remove_unused_layers no)
			(net "P12V")
			(clearance 0)
		)
		(pad "54" thru_hole circle
			(at 5.08 25.4 270)
			(size 1.6256 1.6256)
			(drill 1.1176)
			(layers "*.Cu" "*.Mask")
			(remove_unused_layers no)
			(net "P12V")
			(clearance 0)
		)
		(pad "55" thru_hole circle
			(at 5.08 22.86 270)
			(size 1.6256 1.6256)
			(drill 1.1176)
			(layers "*.Cu" "*.Mask")
			(remove_unused_layers no)
			(net "P12V")
			(clearance 0)
		)
		(pad "56" thru_hole circle
			(at 5.08 20.32 270)
			(size 1.6256 1.6256)
			(drill 1.1176)
			(layers "*.Cu" "*.Mask")
			(remove_unused_layers no)
			(net "P12V")
			(clearance 0)
		)
		(pad "57" thru_hole circle
			(at 5.08 17.78 270)
			(size 1.6256 1.6256)
			(drill 1.1176)
			(layers "*.Cu" "*.Mask")
			(remove_unused_layers no)
			(net "P12V")
			(clearance 0)
		)
		(pad "58" thru_hole circle
			(at 5.08 15.24 270)
			(size 1.6256 1.6256)
			(drill 1.1176)
			(layers "*.Cu" "*.Mask")
			(remove_unused_layers no)
			(net "P12V")
			(clearance 0)
		)
		(pad "59" thru_hole circle
			(at 5.08 12.7 270)
			(size 1.6256 1.6256)
			(drill 1.1176)
			(layers "*.Cu" "*.Mask")
			(remove_unused_layers no)
			(net "P12V")
			(clearance 0)
		)
		(pad "60" thru_hole circle
			(at 5.08 10.16 270)
			(size 1.6256 1.6256)
			(drill 1.1176)
			(layers "*.Cu" "*.Mask")
			(remove_unused_layers no)
			(net "P12V")
			(clearance 0)
		)
		(pad "61" thru_hole circle
			(at 5.08 7.62 270)
			(size 1.6256 1.6256)
			(drill 1.1176)
			(layers "*.Cu" "*.Mask")
			(remove_unused_layers no)
			(net "P12V")
			(clearance 0)
		)
		(pad "62" thru_hole circle
			(at 5.08 5.08 270)
			(size 1.6256 1.6256)
			(drill 1.1176)
			(layers "*.Cu" "*.Mask")
			(remove_unused_layers no)
			(net "P12V")
			(clearance 0)
		)
		(pad "63" thru_hole circle
			(at 5.08 2.54 270)
			(size 1.6256 1.6256)
			(drill 1.1176)
			(layers "*.Cu" "*.Mask")
			(remove_unused_layers no)
			(net "P12V")
			(clearance 0)
		)
		(pad "64" thru_hole circle
			(at 5.08 0 270)
			(size 1.6256 1.6256)
			(drill 1.1176)
			(layers "*.Cu" "*.Mask")
			(remove_unused_layers no)
			(net "P12V")
			(clearance 0)
		)
	)
)
